# S9S_MB_2U (Grand Teton) — schematic netlist excerpt (pin names and nets, part order shuffled) for the footprints in the layout excerpt that follows; sources: Cadence DE-HDL packaged netlist, KiCad conversion of 03242023_DA0F0TMBIJ0_F0T_Motherboard_J_brd_V01_OCP.brd

R995  Q_RES  33.2 1% CHIP  pkg 0402LF  page 236 : A = SMB_S3M_CPU1_SCL ; B = SMB_S3M_CPU1_R_SCL
C1175  Q_CAP  0.1UF 25V 10% X7R  pkg 0402  page 155 : A = P3V3_AUX ; B = GND
PC831  Q_CAP  22UF 16V 20% X6S  pkg C0805  page 281 : A = SW_P12V_PVCCIN_CPU0_FLT ; B = GND

(kicad_pcb
	(version 20260206)
	(generator "pcbnew")
	(generator_version "10.0")
	(general
		(thickness 1.6)
		(legacy_teardrops no)
	)
	(paper "A4")
	(title_block
		(title "03242023_DA0F0TMBIJ0_F0T_Motherboard_J_brd_V01_OCP.brd")
		(comment 1 "Grand Teton / footprints 3011-3013 of 6105")
	)
	(layers
		(0 "F.Cu" signal "TOP")
		(4 "In1.Cu" signal "GND")
		(6 "In2.Cu" signal "IN1")
		(8 "In3.Cu" signal "GND1")
		(10 "In4.Cu" signal "IN2")
		(12 "In5.Cu" signal "GND2")
		(14 "In6.Cu" signal "IN3")
		(16 "In7.Cu" signal "GND3")
		(18 "In8.Cu" signal "VCC")
		(20 "In9.Cu" signal "VCC1")
		(22 "In10.Cu" signal "GND4")
		(24 "In11.Cu" signal "IN4")
		(26 "In12.Cu" signal "GND5")
		(28 "In13.Cu" signal "IN5")
		(30 "In14.Cu" signal "GND6")
		(32 "In15.Cu" signal "IN6")
		(34 "In16.Cu" signal "GND7")
		(2 "B.Cu" signal "BOTTOM")
		(9 "F.Adhes" user "F.Adhesive")
		(11 "B.Adhes" user "B.Adhesive")
		(13 "F.Paste" user "Package Geometry/Pastemask Top")
		(15 "B.Paste" user "Package Geometry/Pastemask Bottom")
		(5 "F.SilkS" user "Ref Des/Silkscreen Top")
		(7 "B.SilkS" user "Ref Des/Silkscreen Bottom")
		(1 "F.Mask" user "Board Geometry/Soldermask Top")
		(3 "B.Mask" user "Board Geometry/Soldermask Bottom")
		(17 "Dwgs.User" user "User.Drawings")
		(19 "Cmts.User" user "User.Comments")
		(21 "Eco1.User" user "User.Eco1")
		(23 "Eco2.User" user "User.Eco2")
		(25 "Edge.Cuts" user "Board Geometry/Outline")
		(27 "Margin" user)
		(31 "F.CrtYd" user "Package Geometry/Place Bound Top")
		(29 "B.CrtYd" user "Package Geometry/Place Bound Bottom")
		(35 "F.Fab" user "Ref Des/Assembly Top")
		(33 "B.Fab" user "Ref Des/Assembly Bottom")
	)
	(footprint ""
		(layer "F.Cu")
		(at 466.68309 -46.408848)
		(property "Reference" "C1175"
			(at 0 0 0)
			(layer "F.SilkS")
			(hide yes)
			(effects
				(font
					(size 1.27 1.27)
				)
			)
		)
		(property "Value" ""
			(at 0 0 0)
			(layer "F.Fab")
			(effects
				(font
					(size 1.27 1.27)
				)
			)
		)
		(duplicate_pad_numbers_are_jumpers no)
		(fp_line
			(start -0.7874 -0.4064)
			(end 0.7874 -0.4064)
			(stroke
				(width 0.1524)
				(type default)
			)
			(layer "F.SilkS")
		)
		(fp_line
			(start -0.7874 0.4064)
			(end -0.7874 -0.4064)
			(stroke
				(width 0.1524)
				(type default)
			)
			(layer "F.SilkS")
		)
		(fp_line
			(start 0.7874 -0.4064)
			(end 0.7874 0.4064)
			(stroke
				(width 0.1524)
				(type default)
			)
			(layer "F.SilkS")
		)
		(fp_line
			(start 0.7874 0.4064)
			(end -0.7874 0.4064)
			(stroke
				(width 0.1524)
				(type default)
			)
			(layer "F.SilkS")
		)
		(fp_line
			(start -0.67945 -0.305054)
			(end -0.12065 -0.305054)
			(stroke
				(width 0.1)
				(type default)
			)
			(layer "F.Fab")
		)
		(fp_line
			(start -0.67945 0.3048)
			(end -0.67945 -0.305054)
			(stroke
				(width 0.1)
				(type default)
			)
			(layer "F.Fab")
		)
		(fp_line
			(start -0.12065 -0.305054)
			(end -0.12065 -0.2794)
			(stroke
				(width 0.1)
				(type default)
			)
			(layer "F.Fab")
		)
		(fp_line
			(start -0.12065 -0.2794)
			(end 0.12065 -0.2794)
			(stroke
				(width 0.1)
				(type default)
			)
			(layer "F.Fab")
		)
		(fp_line
			(start -0.12065 0.2794)
			(end -0.12065 0.3048)
			(stroke
				(width 0.1)
				(type default)
			)
			(layer "F.Fab")
		)
		(fp_line
			(start -0.12065 0.3048)
			(end -0.67945 0.3048)
			(stroke
				(width 0.1)
				(type default)
			)
			(layer "F.Fab")
		)
		(fp_line
			(start 0.120396 0.2794)
			(end -0.12065 0.2794)
			(stroke
				(width 0.1)
				(type default)
			)
			(layer "F.Fab")
		)
		(fp_line
			(start 0.120396 0.3048)
			(end 0.120396 0.2794)
			(stroke
				(width 0.1)
				(type default)
			)
			(layer "F.Fab")
		)
		(fp_line
			(start 0.12065 -0.3048)
			(end 0.67945 -0.3048)
			(stroke
				(width 0.1)
				(type default)
			)
			(layer "F.Fab")
		)
		(fp_line
			(start 0.12065 -0.2794)
			(end 0.12065 -0.3048)
			(stroke
				(width 0.1)
				(type default)
			)
			(layer "F.Fab")
		)
		(fp_line
			(start 0.67945 -0.3048)
			(end 0.67945 0.3048)
			(stroke
				(width 0.1)
				(type default)
			)
			(layer "F.Fab")
		)
		(fp_line
			(start 0.67945 0.3048)
			(end 0.120396 0.3048)
			(stroke
				(width 0.1)
				(type default)
			)
			(layer "F.Fab")
		)
		(pad "1" smd circle
			(at -0.40005 0)
			(size 0 0)
			(layers "F.Cu" "F.Mask" "F.Paste")
			(net "P3V3_AUX")
		)
		(pad "2" smd circle
			(at 0.40005 0)
			(size 0 0)
			(layers "F.Cu" "F.Mask" "F.Paste")
			(net "GND")
		)
	)
	(footprint ""
		(layer "F.Cu")
		(at 374.336056 -354.844858)
		(property "Reference" "PC831"
			(at 0 0 0)
			(layer "F.SilkS")
			(hide yes)
			(effects
				(font
					(size 1.27 1.27)
				)
			)
		)
		(property "Value" ""
			(at 0 0 0)
			(layer "F.Fab")
			(effects
				(font
					(size 1.27 1.27)
				)
			)
		)
		(duplicate_pad_numbers_are_jumpers no)
		(fp_line
			(start -1.524 -0.762)
			(end 1.524 -0.762)
			(stroke
				(width 0.1524)
				(type default)
			)
			(layer "F.SilkS")
		)
		(fp_line
			(start -1.524 0.762)
			(end -1.524 -0.762)
			(stroke
				(width 0.1524)
				(type default)
			)
			(layer "F.SilkS")
		)
		(fp_line
			(start 1.524 -0.762)
			(end 1.524 0.762)
			(stroke
				(width 0.1524)
				(type default)
			)
			(layer "F.SilkS")
		)
		(fp_line
			(start 1.524 0.762)
			(end -1.524 0.762)
			(stroke
				(width 0.1524)
				(type default)
			)
			(layer "F.SilkS")
		)
		(fp_line
			(start -1.1049 -0.724916)
			(end -1.1049 0.724916)
			(stroke
				(width 0.1)
				(type default)
			)
			(layer "F.Fab")
		)
		(fp_line
			(start -1.1049 0.724916)
			(end 1.1049 0.724916)
			(stroke
				(width 0.1)
				(type default)
			)
			(layer "F.Fab")
		)
		(fp_line
			(start 1.1049 -0.724916)
			(end -1.1049 -0.724916)
			(stroke
				(width 0.1)
				(type default)
			)
			(layer "F.Fab")
		)
		(fp_line
			(start 1.1049 0.724916)
			(end 1.1049 -0.724916)
			(stroke
				(width 0.1)
				(type default)
			)
			(layer "F.Fab")
		)
		(pad "1" smd rect
			(at -0.889 0 180)
			(size 1.016 1.27)
			(layers "F.Cu" "F.Mask" "F.Paste")
			(net "SW_P12V_PVCCIN_CPU0_FLT")
		)
		(pad "2" smd rect
			(at 0.889 0 180)
			(size 1.016 1.27)
			(layers "F.Cu" "F.Mask" "F.Paste")
			(net "GND")
		)
	)
	(footprint ""
		(layer "F.Cu")
		(at 225.525838 -220.815916 90)
		(property "Reference" "R995"
			(at 0 0 90)
			(layer "F.SilkS")
			(hide yes)
			(effects
				(font
					(size 1.27 1.27)
				)
			)
		)
		(property "Value" ""
			(at 0 0 90)
			(layer "F.Fab")
			(effects
				(font
					(size 1.27 1.27)
				)
			)
		)
		(duplicate_pad_numbers_are_jumpers no)
		(fp_line
			(start 0.7874 -0.4064)
			(end 0.7874 0.4064)
			(stroke
				(width 0.1524)
				(type default)
			)
			(layer "F.SilkS")
		)
		(fp_line
			(start -0.7874 -0.4064)
			(end 0.7874 -0.4064)
			(stroke
				(width 0.1524)
				(type default)
			)
			(layer "F.SilkS")
		)
		(fp_line
			(start 0.7874 0.4064)
			(end -0.7874 0.4064)
			(stroke
				(width 0.1524)
				(type default)
			)
			(layer "F.SilkS")
		)
		(fp_line
			(start -0.7874 0.4064)
			(end -0.7874 -0.4064)
			(stroke
				(width 0.1524)
				(type default)
			)
			(layer "F.SilkS")
		)
		(fp_line
			(start -0.12065 -0.305054)
			(end -0.12065 -0.2794)
			(stroke
				(width 0.1)
				(type default)
			)
			(layer "F.Fab")
		)
		(fp_line
			(start -0.67945 -0.305054)
			(end -0.12065 -0.305054)
			(stroke
				(width 0.1)
				(type default)
			)
			(layer "F.Fab")
		)
		(fp_line
			(start 0.67945 -0.3048)
			(end 0.67945 0.3048)
			(stroke
				(width 0.1)
				(type default)
			)
			(layer "F.Fab")
		)
		(fp_line
			(start 0.12065 -0.3048)
			(end 0.67945 -0.3048)
			(stroke
				(width 0.1)
				(type default)
			)
			(layer "F.Fab")
		)
		(fp_line
			(start 0.12065 -0.2794)
			(end 0.12065 -0.3048)
			(stroke
				(width 0.1)
				(type default)
			)
			(layer "F.Fab")
		)
		(fp_line
			(start -0.12065 -0.2794)
			(end 0.12065 -0.2794)
			(stroke
				(width 0.1)
				(type default)
			)
			(layer "F.Fab")
		)
		(fp_line
			(start 0.120396 0.2794)
			(end -0.12065 0.2794)
			(stroke
				(width 0.1)
				(type default)
			)
			(layer "F.Fab")
		)
		(fp_line
			(start -0.12065 0.2794)
			(end -0.12065 0.3048)
			(stroke
				(width 0.1)
				(type default)
			)
			(layer "F.Fab")
		)
		(fp_line
			(start 0.67945 0.3048)
			(end 0.120396 0.3048)
			(stroke
				(width 0.1)
				(type default)
			)
			(layer "F.Fab")
		)
		(fp_line
			(start 0.120396 0.3048)
			(end 0.120396 0.2794)
			(stroke
				(width 0.1)
				(type default)
			)
			(layer "F.Fab")
		)
		(fp_line
			(start -0.12065 0.3048)
			(end -0.67945 0.3048)
			(stroke
				(width 0.1)
				(type default)
			)
			(layer "F.Fab")
		)
		(fp_line
			(start -0.67945 0.3048)
			(end -0.67945 -0.305054)
			(stroke
				(width 0.1)
				(type default)
			)
			(layer "F.Fab")
		)
		(pad "1" smd circle
			(at -0.40005 0 90)
			(size 0 0)
			(layers "F.Cu" "F.Mask" "F.Paste")
			(net "SMB_S3M_CPU1_SCL")
		)
		(pad "2" smd circle
			(at 0.40005 0 90)
			(size 0 0)
			(layers "F.Cu" "F.Mask" "F.Paste")
			(net "SMB_S3M_CPU1_R_SCL")
		)
	)
)
